(kicad_pcb
	(version 20260206)
	(generator "pcbnew")
	(generator_version "10.0")
	(general
		(thickness 2.5)
		(legacy_teardrops no)
	)
	(paper "A4")
	(title_block
		(title "discovery-power-board-v1-revB — discovery.kicad_pcb")
		(comment 1 "Discovery / footprints 1-5 of 18")
	)
	(layers
		(0 "F.Cu" signal)
		(2 "B.Cu" signal)
		(9 "F.Adhes" user)
		(11 "B.Adhes" user)
		(13 "F.Paste" user)
		(15 "B.Paste" user)
		(5 "F.SilkS" user)
		(7 "B.SilkS" user)
		(1 "F.Mask" user)
		(3 "B.Mask" user)
		(17 "Dwgs.User" user)
		(19 "Cmts.User" user)
		(21 "Eco1.User" user)
		(23 "Eco2.User" user)
		(25 "Edge.Cuts" user)
		(27 "Margin" user)
		(31 "F.CrtYd" user)
		(29 "B.CrtYd" user)
		(35 "F.Fab" user)
		(33 "B.Fab" user)
	)
	(footprint "discovery:CONN_02x03_4.2mm"
		(layer "F.Cu")
		(at 28 93.5 -90)
		(property "Reference" "J2"
			(at 1.0668 -10.6172 90)
			(layer "F.SilkS")
			(effects
				(font
					(size 1 1)
					(thickness 0.15)
				)
			)
		)
		(property "Value" "Conn_02x03_PCIe"
			(at 6.8961 -11.176 270)
			(layer "F.Fab")
			(effects
				(font
					(size 0.75 0.75)
					(thickness 0.125)
				)
			)
		)
		(attr through_hole)
		(duplicate_pad_numbers_are_jumpers no)
		(fp_line
			(start 0 0)
			(end 13.8 0)
			(stroke
				(width 0.1)
				(type solid)
			)
			(layer "F.SilkS")
		)
		(fp_line
			(start 13.8 0)
			(end 13.8 -9.6)
			(stroke
				(width 0.1)
				(type solid)
			)
			(layer "F.SilkS")
		)
		(fp_line
			(start 0 -9.6)
			(end 0 0)
			(stroke
				(width 0.1)
				(type solid)
			)
			(layer "F.SilkS")
		)
		(fp_line
			(start 5.9 -9.6)
			(end 5.9 -10.4)
			(stroke
				(width 0.1)
				(type solid)
			)
			(layer "F.SilkS")
		)
		(fp_line
			(start 13.8 -9.6)
			(end 0 -9.6)
			(stroke
				(width 0.1)
				(type solid)
			)
			(layer "F.SilkS")
		)
		(fp_line
			(start 5.9 -10.4)
			(end 7.9 -10.4)
			(stroke
				(width 0.1)
				(type solid)
			)
			(layer "F.SilkS")
		)
		(fp_line
			(start 7.9 -10.4)
			(end 7.9 -9.6)
			(stroke
				(width 0.1)
				(type solid)
			)
			(layer "F.SilkS")
		)
		(fp_line
			(start -4 0.05)
			(end 17.8 0.05)
			(stroke
				(width 0.1)
				(type solid)
			)
			(layer "F.CrtYd")
		)
		(fp_line
			(start 17.8 0.05)
			(end 17.8 -10.45)
			(stroke
				(width 0.1)
				(type solid)
			)
			(layer "F.CrtYd")
		)
		(fp_line
			(start -4 -10.45)
			(end -4 0.05)
			(stroke
				(width 0.1)
				(type solid)
			)
			(layer "F.CrtYd")
		)
		(fp_line
			(start 17.8 -10.45)
			(end -4 -10.45)
			(stroke
				(width 0.1)
				(type solid)
			)
			(layer "F.CrtYd")
		)
		(pad "" np_thru_hole circle
			(at -2 -7.1 270)
			(size 4 4)
			(drill 3.03)
			(layers "*.Cu" "*.Mask")
		)
		(pad "" np_thru_hole circle
			(at 15.8 -7.1 270)
			(size 4 4)
			(drill 3.03)
			(layers "*.Cu" "*.Mask")
		)
		(pad "1" thru_hole circle
			(at 11.1 -2.9 270)
			(size 2.5 2.5)
			(drill 1.85)
			(layers "*.Cu" "*.Mask")
			(remove_unused_layers no)
			(net "+12V")
		)
		(pad "2" thru_hole circle
			(at 6.9 -2.9 270)
			(size 2.5 2.5)
			(drill 1.85)
			(layers "*.Cu" "*.Mask")
			(remove_unused_layers no)
			(net "+12V")
		)
		(pad "3" thru_hole circle
			(at 2.7 -2.9 270)
			(size 2.5 2.5)
			(drill 1.85)
			(layers "*.Cu" "*.Mask")
			(remove_unused_layers no)
			(net "+12V")
		)
		(pad "4" thru_hole circle
			(at 11.1 -7.1 270)
			(size 2.5 2.5)
			(drill 1.85)
			(layers "*.Cu" "*.Mask")
			(remove_unused_layers no)
			(net "GND")
		)
		(pad "5" thru_hole circle
			(at 6.9 -7.1 270)
			(size 2.5 2.5)
			(drill 1.85)
			(layers "*.Cu" "*.Mask")
			(remove_unused_layers no)
			(net "GND")
		)
		(pad "6" thru_hole circle
			(at 2.7 -7.1 270)
			(size 2.5 2.5)
			(drill 1.85)
			(layers "*.Cu" "*.Mask")
			(remove_unused_layers no)
			(net "GND")
		)
	)
	(footprint "discovery:CONN_02x03_4.2mm"
		(layer "F.Cu")
		(at 18 107.3 90)
		(property "Reference" "J4"
			(at 12.71672 -10.37492 90)
			(layer "F.SilkS")
			(effects
				(font
					(size 1 1)
					(thickness 0.15)
				)
			)
		)
		(property "Value" "Conn_02x03_PCIe"
			(at 6.8961 -11.176 90)
			(layer "F.Fab")
			(effects
				(font
					(size 0.75 0.75)
					(thickness 0.125)
				)
			)
		)
		(attr through_hole)
		(duplicate_pad_numbers_are_jumpers no)
		(fp_line
			(start 7.9 -10.4)
			(end 7.9 -9.6)
			(stroke
				(width 0.1)
				(type solid)
			)
			(layer "F.SilkS")
		)
		(fp_line
			(start 5.9 -10.4)
			(end 7.9 -10.4)
			(stroke
				(width 0.1)
				(type solid)
			)
			(layer "F.SilkS")
		)
		(fp_line
			(start 13.8 -9.6)
			(end 0 -9.6)
			(stroke
				(width 0.1)
				(type solid)
			)
			(layer "F.SilkS")
		)
		(fp_line
			(start 5.9 -9.6)
			(end 5.9 -10.4)
			(stroke
				(width 0.1)
				(type solid)
			)
			(layer "F.SilkS")
		)
		(fp_line
			(start 0 -9.6)
			(end 0 0)
			(stroke
				(width 0.1)
				(type solid)
			)
			(layer "F.SilkS")
		)
		(fp_line
			(start 13.8 0)
			(end 13.8 -9.6)
			(stroke
				(width 0.1)
				(type solid)
			)
			(layer "F.SilkS")
		)
		(fp_line
			(start 0 0)
			(end 13.8 0)
			(stroke
				(width 0.1)
				(type solid)
			)
			(layer "F.SilkS")
		)
		(fp_line
			(start 17.8 -10.45)
			(end -4 -10.45)
			(stroke
				(width 0.1)
				(type solid)
			)
			(layer "F.CrtYd")
		)
		(fp_line
			(start -4 -10.45)
			(end -4 0.05)
			(stroke
				(width 0.1)
				(type solid)
			)
			(layer "F.CrtYd")
		)
		(fp_line
			(start 17.8 0.05)
			(end 17.8 -10.45)
			(stroke
				(width 0.1)
				(type solid)
			)
			(layer "F.CrtYd")
		)
		(fp_line
			(start -4 0.05)
			(end 17.8 0.05)
			(stroke
				(width 0.1)
				(type solid)
			)
			(layer "F.CrtYd")
		)
		(pad "" np_thru_hole circle
			(at -2 -7.1 90)
			(size 4 4)
			(drill 3.03)
			(layers "*.Cu" "*.Mask")
		)
		(pad "" np_thru_hole circle
			(at 15.8 -7.1 90)
			(size 4 4)
			(drill 3.03)
			(layers "*.Cu" "*.Mask")
		)
		(pad "1" thru_hole circle
			(at 11.1 -2.9 90)
			(size 2.5 2.5)
			(drill 1.85)
			(layers "*.Cu" "*.Mask")
			(remove_unused_layers no)
			(net "+12V")
		)
		(pad "2" thru_hole circle
			(at 6.9 -2.9 90)
			(size 2.5 2.5)
			(drill 1.85)
			(layers "*.Cu" "*.Mask")
			(remove_unused_layers no)
			(net "+12V")
		)
		(pad "3" thru_hole circle
			(at 2.7 -2.9 90)
			(size 2.5 2.5)
			(drill 1.85)
			(layers "*.Cu" "*.Mask")
			(remove_unused_layers no)
			(net "+12V")
		)
		(pad "4" thru_hole circle
			(at 11.1 -7.1 90)
			(size 2.5 2.5)
			(drill 1.85)
			(layers "*.Cu" "*.Mask")
			(remove_unused_layers no)
			(net "GND")
		)
		(pad "5" thru_hole circle
			(at 6.9 -7.1 90)
			(size 2.5 2.5)
			(drill 1.85)
			(layers "*.Cu" "*.Mask")
			(remove_unused_layers no)
			(net "GND")
		)
		(pad "6" thru_hole circle
			(at 2.7 -7.1 90)
			(size 2.5 2.5)
			(drill 1.85)
			(layers "*.Cu" "*.Mask")
			(remove_unused_layers no)
			(net "GND")
		)
	)
	(footprint "discovery:CONN_02x03_4.2mm"
		(layer "F.Cu")
		(at 18 136.1326 90)
		(property "Reference" "J5"
			(at 12.74572 -10.42064 90)
			(layer "F.SilkS")
			(effects
				(font
					(size 1 1)
					(thickness 0.15)
				)
			)
		)
		(property "Value" "Conn_02x03_PCIe"
			(at 6.8961 -11.176 90)
			(layer "F.Fab")
			(effects
				(font
					(size 0.75 0.75)
					(thickness 0.125)
				)
			)
		)
		(attr through_hole)
		(duplicate_pad_numbers_are_jumpers no)
		(fp_line
			(start 7.9 -10.4)
			(end 7.9 -9.6)
			(stroke
				(width 0.1)
				(type solid)
			)
			(layer "F.SilkS")
		)
		(fp_line
			(start 5.9 -10.4)
			(end 7.9 -10.4)
			(stroke
				(width 0.1)
				(type solid)
			)
			(layer "F.SilkS")
		)
		(fp_line
			(start 13.8 -9.6)
			(end 0 -9.6)
			(stroke
				(width 0.1)
				(type solid)
			)
			(layer "F.SilkS")
		)
		(fp_line
			(start 5.9 -9.6)
			(end 5.9 -10.4)
			(stroke
				(width 0.1)
				(type solid)
			)
			(layer "F.SilkS")
		)
		(fp_line
			(start 0 -9.6)
			(end 0 0)
			(stroke
				(width 0.1)
				(type solid)
			)
			(layer "F.SilkS")
		)
		(fp_line
			(start 13.8 0)
			(end 13.8 -9.6)
			(stroke
				(width 0.1)
				(type solid)
			)
			(layer "F.SilkS")
		)
		(fp_line
			(start 0 0)
			(end 13.8 0)
			(stroke
				(width 0.1)
				(type solid)
			)
			(layer "F.SilkS")
		)
		(fp_line
			(start 17.8 -10.45)
			(end -4 -10.45)
			(stroke
				(width 0.1)
				(type solid)
			)
			(layer "F.CrtYd")
		)
		(fp_line
			(start -4 -10.45)
			(end -4 0.05)
			(stroke
				(width 0.1)
				(type solid)
			)
			(layer "F.CrtYd")
		)
		(fp_line
			(start 17.8 0.05)
			(end 17.8 -10.45)
			(stroke
				(width 0.1)
				(type solid)
			)
			(layer "F.CrtYd")
		)
		(fp_line
			(start -4 0.05)
			(end 17.8 0.05)
			(stroke
				(width 0.1)
				(type solid)
			)
			(layer "F.CrtYd")
		)
		(pad "" np_thru_hole circle
			(at -2 -7.1 90)
			(size 4 4)
			(drill 3.03)
			(layers "*.Cu" "*.Mask")
		)
		(pad "" np_thru_hole circle
			(at 15.8 -7.1 90)
			(size 4 4)
			(drill 3.03)
			(layers "*.Cu" "*.Mask")
		)
		(pad "1" thru_hole circle
			(at 11.1 -2.9 90)
			(size 2.5 2.5)
			(drill 1.85)
			(layers "*.Cu" "*.Mask")
			(remove_unused_layers no)
			(net "+12V")
		)
		(pad "2" thru_hole circle
			(at 6.9 -2.9 90)
			(size 2.5 2.5)
			(drill 1.85)
			(layers "*.Cu" "*.Mask")
			(remove_unused_layers no)
			(net "+12V")
		)
		(pad "3" thru_hole circle
			(at 2.7 -2.9 90)
			(size 2.5 2.5)
			(drill 1.85)
			(layers "*.Cu" "*.Mask")
			(remove_unused_layers no)
			(net "+12V")
		)
		(pad "4" thru_hole circle
			(at 11.1 -7.1 90)
			(size 2.5 2.5)
			(drill 1.85)
			(layers "*.Cu" "*.Mask")
			(remove_unused_layers no)
			(net "GND")
		)
		(pad "5" thru_hole circle
			(at 6.9 -7.1 90)
			(size 2.5 2.5)
			(drill 1.85)
			(layers "*.Cu" "*.Mask")
			(remove_unused_layers no)
			(net "GND")
		)
		(pad "6" thru_hole circle
			(at 2.7 -7.1 90)
			(size 2.5 2.5)
			(drill 1.85)
			(layers "*.Cu" "*.Mask")
			(remove_unused_layers no)
			(net "GND")
		)
	)
	(footprint "discovery:CONN_02x03_4.2mm"
		(layer "F.Cu")
		(at 28 122.3326 -90)
		(property "Reference" "J6"
			(at 1.02108 -10.54196 270)
			(layer "F.SilkS")
			(effects
				(font
					(size 1 1)
					(thickness 0.15)
				)
			)
		)
		(property "Value" "Conn_02x03_PCIe"
			(at 6.8961 -11.176 270)
			(layer "F.Fab")
			(effects
				(font
					(size 0.75 0.75)
					(thickness 0.125)
				)
			)
		)
		(attr through_hole)
		(duplicate_pad_numbers_are_jumpers no)
		(fp_line
			(start 0 0)
			(end 13.8 0)
			(stroke
				(width 0.1)
				(type solid)
			)
			(layer "F.SilkS")
		)
		(fp_line
			(start 13.8 0)
			(end 13.8 -9.6)
			(stroke
				(width 0.1)
				(type solid)
			)
			(layer "F.SilkS")
		)
		(fp_line
			(start 0 -9.6)
			(end 0 0)
			(stroke
				(width 0.1)
				(type solid)
			)
			(layer "F.SilkS")
		)
		(fp_line
			(start 5.9 -9.6)
			(end 5.9 -10.4)
			(stroke
				(width 0.1)
				(type solid)
			)
			(layer "F.SilkS")
		)
		(fp_line
			(start 13.8 -9.6)
			(end 0 -9.6)
			(stroke
				(width 0.1)
				(type solid)
			)
			(layer "F.SilkS")
		)
		(fp_line
			(start 5.9 -10.4)
			(end 7.9 -10.4)
			(stroke
				(width 0.1)
				(type solid)
			)
			(layer "F.SilkS")
		)
		(fp_line
			(start 7.9 -10.4)
			(end 7.9 -9.6)
			(stroke
				(width 0.1)
				(type solid)
			)
			(layer "F.SilkS")
		)
		(fp_line
			(start -4 0.05)
			(end 17.8 0.05)
			(stroke
				(width 0.1)
				(type solid)
			)
			(layer "F.CrtYd")
		)
		(fp_line
			(start 17.8 0.05)
			(end 17.8 -10.45)
			(stroke
				(width 0.1)
				(type solid)
			)
			(layer "F.CrtYd")
		)
		(fp_line
			(start -4 -10.45)
			(end -4 0.05)
			(stroke
				(width 0.1)
				(type solid)
			)
			(layer "F.CrtYd")
		)
		(fp_line
			(start 17.8 -10.45)
			(end -4 -10.45)
			(stroke
				(width 0.1)
				(type solid)
			)
			(layer "F.CrtYd")
		)
		(pad "" np_thru_hole circle
			(at -2 -7.1 270)
			(size 4 4)
			(drill 3.03)
			(layers "*.Cu" "*.Mask")
		)
		(pad "" np_thru_hole circle
			(at 15.8 -7.1 270)
			(size 4 4)
			(drill 3.03)
			(layers "*.Cu" "*.Mask")
		)
		(pad "1" thru_hole circle
			(at 11.1 -2.9 270)
			(size 2.5 2.5)
			(drill 1.85)
			(layers "*.Cu" "*.Mask")
			(remove_unused_layers no)
			(net "+12V")
		)
		(pad "2" thru_hole circle
			(at 6.9 -2.9 270)
			(size 2.5 2.5)
			(drill 1.85)
			(layers "*.Cu" "*.Mask")
			(remove_unused_layers no)
			(net "+12V")
		)
		(pad "3" thru_hole circle
			(at 2.7 -2.9 270)
			(size 2.5 2.5)
			(drill 1.85)
			(layers "*.Cu" "*.Mask")
			(remove_unused_layers no)
			(net "+12V")
		)
		(pad "4" thru_hole circle
			(at 11.1 -7.1 270)
			(size 2.5 2.5)
			(drill 1.85)
			(layers "*.Cu" "*.Mask")
			(remove_unused_layers no)
			(net "GND")
		)
		(pad "5" thru_hole circle
			(at 6.9 -7.1 270)
			(size 2.5 2.5)
			(drill 1.85)
			(layers "*.Cu" "*.Mask")
			(remove_unused_layers no)
			(net "GND")
		)
		(pad "6" thru_hole circle
			(at 2.7 -7.1 270)
			(size 2.5 2.5)
			(drill 1.85)
			(layers "*.Cu" "*.Mask")
			(remove_unused_layers no)
			(net "GND")
		)
	)
	(footprint "discovery:CONN_02x04_4.2mm"
		(layer "F.Cu")
		(at 18 81.3 90)
		(property "Reference" "J1"
			(at 17.00276 1.07696 270)
			(layer "F.SilkS")
			(effects
				(font
					(size 1 1)
					(thickness 0.15)
				)
			)
		)
		(property "Value" "Conn_02x04_CPU"
			(at 10.69848 0.8509 90)
			(layer "F.Fab")
			(effects
				(font
					(size 1 1)
					(thickness 0.15)
				)
			)
		)
		(attr through_hole)
		(duplicate_pad_numbers_are_jumpers no)
		(fp_line
			(start 10.2 -11)
			(end 10.2 -9.6)
			(stroke
				(width 0.1)
				(type solid)
			)
			(layer "F.SilkS")
		)
		(fp_line
			(start 8.2 -11)
			(end 10.2 -11)
			(stroke
				(width 0.1)
				(type solid)
			)
			(layer "F.SilkS")
		)
		(fp_line
			(start 8.2 -11)
			(end 8.2 -9.6)
			(stroke
				(width 0.1)
				(type solid)
			)
			(layer "F.SilkS")
		)
		(fp_line
			(start 0 -9.6)
			(end 18 -9.6)
			(stroke
				(width 0.1)
				(type solid)
			)
			(layer "F.SilkS")
		)
		(fp_line
			(start 18 0)
			(end 18 -9.6)
			(stroke
				(width 0.1)
				(type solid)
			)
			(layer "F.SilkS")
		)
		(fp_line
			(start 0 0)
			(end 0 -9.6)
			(stroke
				(width 0.1)
				(type solid)
			)
			(layer "F.SilkS")
		)
		(fp_line
			(start 0 0)
			(end 18 0)
			(stroke
				(width 0.1)
				(type solid)
			)
			(layer "F.SilkS")
		)
		(fp_line
			(start 22 -11.05)
			(end -4 -11.05)
			(stroke
				(width 0.1)
				(type solid)
			)
			(layer "F.CrtYd")
		)
		(fp_line
			(start -4 -11.05)
			(end -4 0.1)
			(stroke
				(width 0.1)
				(type solid)
			)
			(layer "F.CrtYd")
		)
		(fp_line
			(start 22 0.1)
			(end 22 -11.05)
			(stroke
				(width 0.1)
				(type solid)
			)
			(layer "F.CrtYd")
		)
		(fp_line
			(start -4 0.1)
			(end 22 0.1)
			(stroke
				(width 0.1)
				(type solid)
			)
			(layer "F.CrtYd")
		)
		(pad "" np_thru_hole circle
			(at -2 -7.1 90)
			(size 4 4)
			(drill 3.03)
			(layers "*.Cu" "*.Mask")
		)
		(pad "" np_thru_hole circle
			(at 20 -7.1 90)
			(size 4 4)
			(drill 3.03)
			(layers "*.Cu" "*.Mask")
		)
		(pad "1" thru_hole circle
			(at 15.3 -2.7 90)
			(size 2.5 2.5)
			(drill 1.8)
			(layers "*.Cu" "*.Mask")
			(remove_unused_layers no)
			(net "GND")
		)
		(pad "2" thru_hole circle
			(at 11.1 -2.7 90)
			(size 2.5 2.5)
			(drill 1.8)
			(layers "*.Cu" "*.Mask")
			(remove_unused_layers no)
			(net "GND")
		)
		(pad "3" thru_hole circle
			(at 6.9 -2.7 90)
			(size 2.5 2.5)
			(drill 1.8)
			(layers "*.Cu" "*.Mask")
			(remove_unused_layers no)
			(net "GND")
		)
		(pad "4" thru_hole circle
			(at 2.7 -2.7 90)
			(size 2.5 2.5)
			(drill 1.8)
			(layers "*.Cu" "*.Mask")
			(remove_unused_layers no)
			(net "GND")
		)
		(pad "5" thru_hole circle
			(at 15.3 -6.9 90)
			(size 2.5 2.5)
			(drill 1.8)
			(layers "*.Cu" "*.Mask")
			(remove_unused_layers no)
			(net "+12V")
		)
		(pad "6" thru_hole circle
			(at 11.1 -6.9 90)
			(size 2.5 2.5)
			(drill 1.8)
			(layers "*.Cu" "*.Mask")
			(remove_unused_layers no)
			(net "+12V")
		)
		(pad "7" thru_hole circle
			(at 6.9 -6.9 90)
			(size 2.5 2.5)
			(drill 1.8)
			(layers "*.Cu" "*.Mask")
			(remove_unused_layers no)
			(net "+12V")
		)
		(pad "8" thru_hole circle
			(at 2.7 -6.9 90)
			(size 2.5 2.5)
			(drill 1.8)
			(layers "*.Cu" "*.Mask")
			(remove_unused_layers no)
			(net "+12V")
		)
	)
)
